# S9S_MB_2U (Grand Teton) — schematic netlist excerpt (pin names and nets, part order shuffled) for the footprints in the layout excerpt that follows; sources: Cadence DE-HDL packaged netlist, KiCad conversion of 03242023_DA0F0TMBIJ0_F0T_Motherboard_J_brd_V01_OCP.brd

PU43_P0_1  ISL99390FRZTR5935  ISL99390FRZ-TR5935 IC  pkg QFN21_6X5XB  page 275
  VOS  = PVCCINFAON_CPU0_VOS1
  AGND  = GND
  VCC  = PVCCINFAON_CPU0_VDD1
  PVCC  = PVCCFA_EHV_CPU0_PVCC
  PGND1  = GND
  GL1  = NC
  PGND2  = GND
  SW  = SW_PVCCINFAON_CPU0_SW1
  VIN1  = SW_P12V_PVCCINFAON_CPU0_FLT
  VIN2  = SW_P12V_PVCCINFAON_CPU0_FLT
  DNC  = NC
  PHASE  = SW_PVCCINFAON_CPU0_BOOTR1
  BOOT  = SW_PVCCINFAON_CPU0_BOOT1
  PWM  = PVCCINFAON_CPU0_APWM1
  EN  = PVCCINFAON_CPU0_VDD1
  TOUT_FLT  = PVCCINFAON_CPU0_ATSEN
  LSET  = PVCCINFAON_CPU0_LSET1
  IOUT  = PVCCINFAON_CPU0_ACSP1
  REFIN  = PVCCINFAON_CPU0_VREF
  PGND3  = GND
  GL2  = NC

(kicad_pcb
	(version 20260206)
	(generator "pcbnew")
	(generator_version "10.0")
	(general
		(thickness 1.6)
		(legacy_teardrops no)
	)
	(paper "A4")
	(title_block
		(title "03242023_DA0F0TMBIJ0_F0T_Motherboard_J_brd_V01_OCP.brd")
		(comment 1 "Grand Teton / footprints 258-258 of 6105")
	)
	(layers
		(0 "F.Cu" signal "TOP")
		(4 "In1.Cu" signal "GND")
		(6 "In2.Cu" signal "IN1")
		(8 "In3.Cu" signal "GND1")
		(10 "In4.Cu" signal "IN2")
		(12 "In5.Cu" signal "GND2")
		(14 "In6.Cu" signal "IN3")
		(16 "In7.Cu" signal "GND3")
		(18 "In8.Cu" signal "VCC")
		(20 "In9.Cu" signal "VCC1")
		(22 "In10.Cu" signal "GND4")
		(24 "In11.Cu" signal "IN4")
		(26 "In12.Cu" signal "GND5")
		(28 "In13.Cu" signal "IN5")
		(30 "In14.Cu" signal "GND6")
		(32 "In15.Cu" signal "IN6")
		(34 "In16.Cu" signal "GND7")
		(2 "B.Cu" signal "BOTTOM")
		(9 "F.Adhes" user "F.Adhesive")
		(11 "B.Adhes" user "B.Adhesive")
		(13 "F.Paste" user "Package Geometry/Pastemask Top")
		(15 "B.Paste" user "Package Geometry/Pastemask Bottom")
		(5 "F.SilkS" user "Ref Des/Silkscreen Top")
		(7 "B.SilkS" user "Ref Des/Silkscreen Bottom")
		(1 "F.Mask" user "Board Geometry/Soldermask Top")
		(3 "B.Mask" user "Board Geometry/Soldermask Bottom")
		(17 "Dwgs.User" user "User.Drawings")
		(19 "Cmts.User" user "User.Comments")
		(21 "Eco1.User" user "User.Eco1")
		(23 "Eco2.User" user "User.Eco2")
		(25 "Edge.Cuts" user "Board Geometry/Outline")
		(27 "Margin" user)
		(31 "F.CrtYd" user "Package Geometry/Place Bound Top")
		(29 "B.CrtYd" user "Package Geometry/Place Bound Bottom")
		(35 "F.Fab" user "Ref Des/Assembly Top")
		(33 "B.Fab" user "Ref Des/Assembly Bottom")
	)
	(footprint ""
		(layer "F.Cu")
		(at 416.009582 -170.821858 -90)
		(property "Reference" "PU43_P0_1"
			(at -4.59486 -6.229858 0)
			(unlocked yes)
			(layer "F.SilkS")
			(effects
				(font
					(size 0.7874 0.5842)
					(thickness 0.1524)
				)
				(justify left)
			)
		)
		(property "Value" ""
			(at 0 0 270)
			(layer "F.Fab")
			(effects
				(font
					(size 1.27 1.27)
				)
			)
		)
		(duplicate_pad_numbers_are_jumpers no)
		(fp_line
			(start -2.500122 2.999994)
			(end -2.500122 2.339594)
			(stroke
				(width 0.1524)
				(type default)
			)
			(layer "F.SilkS")
		)
		(fp_line
			(start -2.2987 2.999994)
			(end -2.500122 2.999994)
			(stroke
				(width 0.1524)
				(type default)
			)
			(layer "F.SilkS")
		)
		(fp_line
			(start 2.500122 2.999994)
			(end 2.2987 2.999994)
			(stroke
				(width 0.1524)
				(type default)
			)
			(layer "F.SilkS")
		)
		(fp_line
			(start 2.500122 2.339594)
			(end 2.500122 2.999994)
			(stroke
				(width 0.1524)
				(type default)
			)
			(layer "F.SilkS")
		)
		(fp_line
			(start -2.500122 0.6604)
			(end -2.500122 0.229108)
			(stroke
				(width 0.1524)
				(type default)
			)
			(layer "F.SilkS")
		)
		(fp_line
			(start -2.500122 -2.529078)
			(end -2.500122 -2.999994)
			(stroke
				(width 0.1524)
				(type default)
			)
			(layer "F.SilkS")
		)
		(fp_line
			(start -2.500122 -2.999994)
			(end -2.24409 -2.999994)
			(stroke
				(width 0.1524)
				(type default)
			)
			(layer "F.SilkS")
		)
		(fp_line
			(start 2.31394 -2.999994)
			(end 2.500122 -2.999994)
			(stroke
				(width 0.1524)
				(type default)
			)
			(layer "F.SilkS")
		)
		(fp_line
			(start 2.500122 -2.999994)
			(end 2.500122 -2.44348)
			(stroke
				(width 0.1524)
				(type default)
			)
			(layer "F.SilkS")
		)
		(fp_poly
			(pts
				(xy -4.215892 -2.236978) (xy -5.231892 -1.728978) (xy -5.231892 -2.744978)
			)
			(stroke
				(width 0)
				(type default)
			)
			(fill yes)
			(layer "F.SilkS")
		)
		(fp_line
			(start -2.500122 2.999994)
			(end -2.500122 -2.999994)
			(stroke
				(width 0.1)
				(type default)
			)
			(layer "F.Fab")
		)
		(fp_line
			(start 2.500122 2.999994)
			(end -2.500122 2.999994)
			(stroke
				(width 0.1)
				(type default)
			)
			(layer "F.Fab")
		)
		(fp_line
			(start -2.500122 -2.999994)
			(end 2.500122 -2.999994)
			(stroke
				(width 0.1)
				(type default)
			)
			(layer "F.Fab")
		)
		(fp_line
			(start 2.500122 -2.999994)
			(end 2.500122 2.999994)
			(stroke
				(width 0.1)
				(type default)
			)
			(layer "F.Fab")
		)
		(fp_poly
			(pts
				(xy -4.218432 -2.783078) (xy -4.218432 -1.767078) (xy -3.202432 -2.275078)
			)
			(stroke
				(width 0)
				(type default)
			)
			(fill yes)
			(layer "F.Fab")
		)
		(pad "1" smd rect
			(at -2.400046 -2.275078)
			(size 0.2286 0.6096)
			(layers "F.Cu" "F.Mask" "F.Paste")
			(net "PVCCINFAON_CPU0_VOS1")
		)
		(pad "2" smd rect
			(at -2.400046 -1.82499)
			(size 0.2286 0.6096)
			(layers "F.Cu" "F.Mask" "F.Paste")
			(net "GND")
		)
		(pad "3" smd rect
			(at -2.400046 -1.374902)
			(size 0.2286 0.6096)
			(layers "F.Cu" "F.Mask" "F.Paste")
			(net "PVCCINFAON_CPU0_VDD1")
		)
		(pad "4" smd rect
			(at -2.400046 -0.925068)
			(size 0.2286 0.6096)
			(layers "F.Cu" "F.Mask" "F.Paste")
			(net "PVCCFA_EHV_CPU0_PVCC")
		)
		(pad "5" smd rect
			(at -2.400046 -0.47498)
			(size 0.2286 0.6096)
			(layers "F.Cu" "F.Mask" "F.Paste")
			(net "GND")
		)
		(pad "6" smd rect
			(at -2.400046 -0.024892)
			(size 0.2286 0.6096)
			(layers "F.Cu" "F.Mask" "F.Paste")
			(net "Net_1923")
		)
		(pad "7_9-20_24" smd circle
			(at 0 1.150112)
			(size 0 0)
			(layers "F.Cu" "F.Mask" "F.Paste")
			(net "GND")
		)
		(pad "10_19" smd rect
			(at 0 2.899918)
			(size 0.6096 4.318)
			(layers "F.Cu" "F.Mask" "F.Paste")
			(net "SW_PVCCINFAON_CPU0_SW1")
		)
		(pad "25_29" smd rect
			(at 1.549908 -1.279906 180)
			(size 2.0574 2.3114)
			(layers "F.Cu" "F.Mask" "F.Paste")
			(net "SW_P12V_PVCCINFAON_CPU0_FLT")
		)
		(pad "30" smd rect
			(at 2.05994 -2.899918 270)
			(size 0.2286 0.6096)
			(layers "F.Cu" "F.Mask" "F.Paste")
			(net "SW_P12V_PVCCINFAON_CPU0_FLT")
		)
		(pad "31" smd rect
			(at 1.610106 -2.899918 270)
			(size 0.2286 0.6096)
			(layers "F.Cu" "F.Mask" "F.Paste")
			(net "Net_1922")
		)
		(pad "32" smd rect
			(at 1.160018 -2.899918 270)
			(size 0.2286 0.6096)
			(layers "F.Cu" "F.Mask" "F.Paste")
			(net "SW_PVCCINFAON_CPU0_BOOTR1")
		)
		(pad "33" smd rect
			(at 0.70993 -2.899918 270)
			(size 0.2286 0.6096)
			(layers "F.Cu" "F.Mask" "F.Paste")
			(net "SW_PVCCINFAON_CPU0_BOOT1")
		)
		(pad "34" smd rect
			(at 0.260096 -2.899918 270)
			(size 0.2286 0.6096)
			(layers "F.Cu" "F.Mask" "F.Paste")
			(net "PVCCINFAON_CPU0_APWM1")
		)
		(pad "35" smd rect
			(at -0.189992 -2.899918 270)
			(size 0.2286 0.6096)
			(layers "F.Cu" "F.Mask" "F.Paste")
			(net "PVCCINFAON_CPU0_VDD1")
		)
		(pad "36" smd rect
			(at -0.64008 -2.899918 270)
			(size 0.2286 0.6096)
			(layers "F.Cu" "F.Mask" "F.Paste")
			(net "PVCCINFAON_CPU0_ATSEN")
		)
		(pad "37" smd rect
			(at -1.089914 -2.899918 270)
			(size 0.2286 0.6096)
			(layers "F.Cu" "F.Mask" "F.Paste")
			(net "PVCCINFAON_CPU0_LSET1")
		)
		(pad "38" smd rect
			(at -1.540002 -2.899918 270)
			(size 0.2286 0.6096)
			(layers "F.Cu" "F.Mask" "F.Paste")
			(net "PVCCINFAON_CPU0_ACSP1")
		)
		(pad "39" smd rect
			(at -1.99009 -2.899918 270)
			(size 0.2286 0.6096)
			(layers "F.Cu" "F.Mask" "F.Paste")
			(net "PVCCINFAON_CPU0_VREF")
		)
		(pad "40" smd rect
			(at -0.87503 -1.27508 270)
			(size 1.7526 1.9558)
			(layers "F.Cu" "F.Mask" "F.Paste")
			(net "GND")
		)
		(pad "41" smd rect
			(at -1.525016 0.249936 180)
			(size 0.3048 0.4572)
			(layers "F.Cu" "F.Mask" "F.Paste")
			(net "Net_1924")
		)
	)
)
